FILE_TYPE = MACRO_DRAWING;
SET COLOR_WIRE YELLOW;
SET COLOR_PROP ORANGE;
SET COLOR_DOT WHITE;
SET COLOR_ARC YELLOW;
SET COLOR_BODY GREEN;
SET COLOR_NOTE PURPLE;
SET PROP_DISPLAY VALUE;
SET PAGE_NUMBER P127;
FORCEADD Q_RES..2
(-1900 2975);
FORCEPROP 1 LAST PART_NUMBER CS31002FB08
J 0
(-1860 2850);
DISPLAY 0.510638 (-1860 2850);
DISPLAY INVISIBLE (-1860 2850);
FORCEPROP 1 LAST VALUE 10K
J 0
(-1855 3050);
DISPLAY 0.638298 (-1855 3050);
FORCEPROP 1 LAST WATTAGE 1/16W
J 0
(-1860 2950);
DISPLAY 0.638298 (-1860 2950);
FORCEPROP 1 LAST TOLERANCE 1%
J 0
(-1855 3000);
DISPLAY 0.638298 (-1855 3000);
FORCEPROP 1 LAST PACK_TYPE 0402LF
J 0
(-1860 2850);
DISPLAY 0.638298 (-1860 2850);
FORCEPROP 1 LAST MATERIAL CHIP
J 0
(-1860 2900);
DISPLAY 0.638298 (-1860 2900);
FORCEPROP 1 LAST $LOCATION R334
J 0
(-1855 3100);
DISPLAY 0.978723 (-1855 3100);
FORCEPROP 1 LASTPIN (-1900 3075) $PN 1
J 0
(-1895 3037);
DISPLAY 0.787234 (-1895 3037);
FORCEPROP 1 LASTPIN (-1900 2875) $PN 2
J 0
(-1895 2885);
DISPLAY 0.787234 (-1895 2885);
FORCEPROP 2 LAST CDS_LIB pure_quanta
J 0
(-1900 2975);
PAINT MONO (-1900 2975);
DISPLAY INVISIBLE (-1900 2975);
FORCEPROP 1 LAST PATH I1
J 0
(-1850 3150);
DISPLAY 0.978723 (-1850 3150);
PAINT WHITE (-1850 3150);
DISPLAY INVISIBLE (-1850 3150);
FORCEPROP 2 LAST CDS_LOCATION R334
J 0
(-1850 3200);
DISPLAY 1.021277 (-1850 3200);
DISPLAY INVISIBLE (-1850 3200);
FORCEPROP 2 LAST $SEC 1
J 0
(-1850 3200);
DISPLAY 0.680851 (-1850 3200);
PAINT MONO (-1850 3200);
DISPLAY INVISIBLE (-1850 3200);
FORCEPROP 2 LAST CDS_SEC 1
J 0
(-1850 3200);
DISPLAY 1.021277 (-1850 3200);
DISPLAY INVISIBLE (-1850 3200);
FORCEADD OFFPAGE..2
(2750 3350);
FORCEPROP 2 LAST $XR0 45 
J 0
(2939 3350);
DISPLAY 0.638298 (2939 3350);
PAINT MONO (2939 3350);
FORCEPROP 2 LAST CDS_LIB standard
J 0
(2750 3350);
PAINT MONO (2750 3350);
DISPLAY INVISIBLE (2750 3350);
FORCEPROP 1 LAST OFFPAGE TRUE
J 0
(3075 3225);
DISPLAY 0.872340 (3075 3225);
DISPLAY INVISIBLE (3075 3225);
FORCEPROP 1 LAST COMMENT_BODY TRUE
J 0
(2705 3255);
DISPLAY 0.872340 (2705 3255);
PAINT GREEN (2705 3255);
DISPLAY INVISIBLE (2705 3255);
FORCEPROP 2 LAST PATH I10
J 0
(2950 3400);
DISPLAY 1.021277 (2950 3400);
DISPLAY INVISIBLE (2950 3400);
FORCEADD OFFPAGE..2
(2750 3275);
FORCEPROP 2 LAST $XR0 45 
J 0
(2939 3275);
DISPLAY 0.638298 (2939 3275);
PAINT MONO (2939 3275);
FORCEPROP 2 LAST CDS_LIB standard
J 0
(2750 3275);
PAINT MONO (2750 3275);
DISPLAY INVISIBLE (2750 3275);
FORCEPROP 1 LAST OFFPAGE TRUE
J 0
(3075 3150);
DISPLAY 0.872340 (3075 3150);
DISPLAY INVISIBLE (3075 3150);
FORCEPROP 1 LAST COMMENT_BODY TRUE
J 0
(2705 3180);
DISPLAY 0.872340 (2705 3180);
PAINT GREEN (2705 3180);
DISPLAY INVISIBLE (2705 3180);
FORCEPROP 2 LAST PATH I11
J 0
(2950 3325);
DISPLAY 1.021277 (2950 3325);
DISPLAY INVISIBLE (2950 3325);
FORCEADD OFFPAGE..2
(2750 3200);
FORCEPROP 2 LAST $XR0 45 
J 0
(2939 3200);
DISPLAY 0.638298 (2939 3200);
PAINT MONO (2939 3200);
FORCEPROP 2 LAST CDS_LIB standard
J 0
(2750 3200);
PAINT MONO (2750 3200);
DISPLAY INVISIBLE (2750 3200);
FORCEPROP 1 LAST OFFPAGE TRUE
J 0
(3075 3075);
DISPLAY 0.872340 (3075 3075);
DISPLAY INVISIBLE (3075 3075);
FORCEPROP 1 LAST COMMENT_BODY TRUE
J 0
(2705 3105);
DISPLAY 0.872340 (2705 3105);
PAINT GREEN (2705 3105);
DISPLAY INVISIBLE (2705 3105);
FORCEPROP 2 LAST PATH I12
J 0
(2950 3250);
DISPLAY 1.021277 (2950 3250);
DISPLAY INVISIBLE (2950 3250);
FORCEADD Q_RES..2
(1625 3625);
FORCEPROP 1 LAST PART_NUMBER CS21002FB06
J 0
(1665 3500);
DISPLAY 0.638298 (1665 3500);
DISPLAY INVISIBLE (1665 3500);
FORCEPROP 1 LAST PACK_TYPE 0402LF
J 0
(1665 3450);
DISPLAY 0.638298 (1665 3450);
FORCEPROP 1 LAST MATERIAL CHIP
J 0
(1665 3550);
DISPLAY 0.638298 (1665 3550);
FORCEPROP 1 LAST WATTAGE 1/16W
J 0
(1665 3600);
DISPLAY 0.638298 (1665 3600);
FORCEPROP 1 LAST VALUE 1K
J 0
(1670 3700);
DISPLAY 0.638298 (1670 3700);
FORCEPROP 1 LAST TOLERANCE 1%
J 0
(1670 3650);
DISPLAY 0.638298 (1670 3650);
FORCEPROP 1 LAST $LOCATION R629
J 0
(1670 3750);
DISPLAY 0.978723 (1670 3750);
FORCEPROP 1 LASTPIN (1625 3725) $PN 1
J 0
(1630 3687);
DISPLAY 0.787234 (1630 3687);
FORCEPROP 1 LASTPIN (1625 3525) $PN 2
J 0
(1630 3535);
DISPLAY 0.787234 (1630 3535);
FORCEPROP 2 LAST CDS_LIB pure_quanta
J 0
(1625 3625);
PAINT MONO (1625 3625);
DISPLAY INVISIBLE (1625 3625);
FORCEPROP 1 LAST PATH I13
J 0
(1675 3800);
DISPLAY 0.978723 (1675 3800);
PAINT WHITE (1675 3800);
DISPLAY INVISIBLE (1675 3800);
FORCEPROP 2 LAST CDS_LOCATION R629
J 0
(1675 3850);
DISPLAY 1.021277 (1675 3850);
DISPLAY INVISIBLE (1675 3850);
FORCEPROP 2 LAST $SEC 1
J 0
(1675 3850);
DISPLAY 0.680851 (1675 3850);
PAINT MONO (1675 3850);
DISPLAY INVISIBLE (1675 3850);
FORCEPROP 2 LAST CDS_SEC 1
J 0
(1675 3850);
DISPLAY 1.021277 (1675 3850);
DISPLAY INVISIBLE (1675 3850);
FORCEADD Q_RES..2
(1350 3625);
FORCEPROP 1 LAST PART_NUMBER CS21002FB06
J 0
(1390 3500);
DISPLAY 0.510638 (1390 3500);
DISPLAY INVISIBLE (1390 3500);
FORCEPROP 1 LAST PACK_TYPE 0402LF
J 0
(1390 3500);
DISPLAY 0.638298 (1390 3500);
FORCEPROP 1 LAST MATERIAL EMPTY
J 0
(1390 3550);
DISPLAY 0.638298 (1390 3550);
PAINT RED (1390 3550);
FORCEPROP 1 LAST VALUE 1K
J 0
(1395 3700);
DISPLAY 0.638298 (1395 3700);
FORCEPROP 1 LAST WATTAGE 1/16W
J 0
(1390 3600);
DISPLAY 0.638298 (1390 3600);
FORCEPROP 1 LAST TOLERANCE 1%
J 0
(1395 3650);
DISPLAY 0.638298 (1395 3650);
FORCEPROP 1 LAST $LOCATION R627
J 0
(1395 3750);
DISPLAY 0.978723 (1395 3750);
FORCEPROP 1 LASTPIN (1350 3725) $PN 1
J 0
(1355 3687);
DISPLAY 0.787234 (1355 3687);
FORCEPROP 1 LASTPIN (1350 3525) $PN 2
J 0
(1355 3535);
DISPLAY 0.787234 (1355 3535);
FORCEPROP 2 LAST CDS_LIB pure_quanta
J 0
(1350 3625);
PAINT MONO (1350 3625);
DISPLAY INVISIBLE (1350 3625);
FORCEPROP 1 LAST PATH I14
J 0
(1400 3800);
DISPLAY 0.978723 (1400 3800);
PAINT WHITE (1400 3800);
DISPLAY INVISIBLE (1400 3800);
FORCEPROP 2 LAST CDS_LOCATION R627
J 0
(1400 3850);
DISPLAY 1.021277 (1400 3850);
DISPLAY INVISIBLE (1400 3850);
FORCEPROP 2 LAST $SEC 1
J 0
(1400 3850);
DISPLAY 0.680851 (1400 3850);
PAINT MONO (1400 3850);
DISPLAY INVISIBLE (1400 3850);
FORCEPROP 2 LAST CDS_SEC 1
J 0
(1400 3850);
DISPLAY 1.021277 (1400 3850);
DISPLAY INVISIBLE (1400 3850);
FORCEADD Q_RES..2
(1625 2975);
FORCEPROP 1 LAST PART_NUMBER CS31002FB08
J 0
(1665 2850);
DISPLAY 0.510638 (1665 2850);
DISPLAY INVISIBLE (1665 2850);
FORCEPROP 1 LAST VALUE 10K
J 0
(1670 3050);
DISPLAY 0.638298 (1670 3050);
FORCEPROP 1 LAST MATERIAL EMPTY
J 0
(1665 2900);
DISPLAY 0.638298 (1665 2900);
PAINT RED (1665 2900);
FORCEPROP 1 LAST WATTAGE 1/16W
J 0
(1665 2950);
DISPLAY 0.638298 (1665 2950);
FORCEPROP 1 LAST PACK_TYPE 0402LF
J 0
(1665 2800);
DISPLAY 0.638298 (1665 2800);
FORCEPROP 1 LAST TOLERANCE 1%
J 0
(1670 3000);
DISPLAY 0.638298 (1670 3000);
FORCEPROP 1 LAST $LOCATION R630
J 0
(1670 3100);
DISPLAY 0.978723 (1670 3100);
FORCEPROP 1 LASTPIN (1625 3075) $PN 1
J 0
(1630 3037);
DISPLAY 0.787234 (1630 3037);
FORCEPROP 1 LASTPIN (1625 2875) $PN 2
J 0
(1630 2885);
DISPLAY 0.787234 (1630 2885);
FORCEPROP 2 LAST CDS_LIB pure_quanta
J 0
(1625 2975);
PAINT MONO (1625 2975);
DISPLAY INVISIBLE (1625 2975);
FORCEPROP 1 LAST PATH I15
J 0
(1675 3150);
DISPLAY 0.978723 (1675 3150);
PAINT WHITE (1675 3150);
DISPLAY INVISIBLE (1675 3150);
FORCEPROP 2 LAST CDS_LOCATION R630
J 0
(1675 3200);
DISPLAY 1.021277 (1675 3200);
DISPLAY INVISIBLE (1675 3200);
FORCEPROP 2 LAST $SEC 1
J 0
(1675 3200);
DISPLAY 0.680851 (1675 3200);
PAINT MONO (1675 3200);
DISPLAY INVISIBLE (1675 3200);
FORCEPROP 2 LAST CDS_SEC 1
J 0
(1675 3200);
DISPLAY 1.021277 (1675 3200);
DISPLAY INVISIBLE (1675 3200);
FORCEADD UNIVERSAL_GND..1
(1625 2750);
FORCEPROP 3 LASTPIN (1625 2800) SIG_NAME GND\g
J 0
(1635 2810);
DISPLAY 0.659574 (1635 2810);
PAINT MONO (1635 2810);
DISPLAY INVISIBLE (1635 2810);
FORCEPROP 2 LAST CDS_LIB logical_power
J 0
(1625 2750);
PAINT MONO (1625 2750);
DISPLAY INVISIBLE (1625 2750);
FORCEPROP 1 LAST HDL_POWER GND
J 1
(1650 2675);
DISPLAY 0.872340 (1650 2675);
PAINT GREEN (1650 2675);
DISPLAY INVISIBLE (1650 2675);
FORCEPROP 1 LAST PATH I16
J 0
(1700 2750);
DISPLAY 0.872340 (1700 2750);
PAINT AQUA (1700 2750);
DISPLAY INVISIBLE (1700 2750);
FORCEADD Q_RES..2
(1350 2975);
FORCEPROP 1 LAST PART_NUMBER CS31002FB08
J 0
(1390 2850);
DISPLAY 0.510638 (1390 2850);
DISPLAY INVISIBLE (1390 2850);
FORCEPROP 1 LAST TOLERANCE 1%
J 0
(1395 3000);
DISPLAY 0.638298 (1395 3000);
FORCEPROP 1 LAST WATTAGE 1/16W
J 0
(1390 2950);
DISPLAY 0.638298 (1390 2950);
FORCEPROP 1 LAST MATERIAL CHIP
J 0
(1390 2900);
DISPLAY 0.638298 (1390 2900);
FORCEPROP 1 LAST VALUE 10K
J 0
(1395 3050);
DISPLAY 0.638298 (1395 3050);
FORCEPROP 1 LAST PACK_TYPE 0402LF
J 0
(1390 2850);
DISPLAY 0.638298 (1390 2850);
FORCEPROP 1 LAST $LOCATION R628
J 0
(1395 3100);
DISPLAY 0.978723 (1395 3100);
FORCEPROP 1 LASTPIN (1350 3075) $PN 1
J 0
(1355 3037);
DISPLAY 0.787234 (1355 3037);
FORCEPROP 1 LASTPIN (1350 2875) $PN 2
J 0
(1355 2885);
DISPLAY 0.787234 (1355 2885);
FORCEPROP 2 LAST CDS_LIB pure_quanta
J 0
(1350 2975);
PAINT MONO (1350 2975);
DISPLAY INVISIBLE (1350 2975);
FORCEPROP 1 LAST PATH I17
J 0
(1400 3150);
DISPLAY 0.978723 (1400 3150);
PAINT WHITE (1400 3150);
DISPLAY INVISIBLE (1400 3150);
FORCEPROP 2 LAST CDS_LOCATION R628
J 0
(1400 3200);
DISPLAY 1.021277 (1400 3200);
DISPLAY INVISIBLE (1400 3200);
FORCEPROP 2 LAST $SEC 1
J 0
(1400 3200);
DISPLAY 0.680851 (1400 3200);
PAINT MONO (1400 3200);
DISPLAY INVISIBLE (1400 3200);
FORCEPROP 2 LAST CDS_SEC 1
J 0
(1400 3200);
DISPLAY 1.021277 (1400 3200);
DISPLAY INVISIBLE (1400 3200);
FORCEADD UNIVERSAL_GND..1
(1350 2750);
FORCEPROP 3 LASTPIN (1350 2800) SIG_NAME GND\g
J 0
(1360 2810);
DISPLAY 0.659574 (1360 2810);
PAINT MONO (1360 2810);
DISPLAY INVISIBLE (1360 2810);
FORCEPROP 2 LAST CDS_LIB logical_power
J 0
(1350 2750);
PAINT MONO (1350 2750);
DISPLAY INVISIBLE (1350 2750);
FORCEPROP 1 LAST HDL_POWER GND
J 1
(1375 2675);
DISPLAY 0.872340 (1375 2675);
PAINT GREEN (1375 2675);
DISPLAY INVISIBLE (1375 2675);
FORCEPROP 1 LAST PATH I18
J 0
(1425 2750);
DISPLAY 0.872340 (1425 2750);
PAINT AQUA (1425 2750);
DISPLAY INVISIBLE (1425 2750);
FORCEADD UNIVERSAL_POWER..1
(-2175 4000);
FORCEPROP 3 LASTPIN (-2175 3950) SIG_NAME P3V3_AUX\g
J 0
(-2165 3960);
DISPLAY 0.659574 (-2165 3960);
PAINT MONO (-2165 3960);
DISPLAY INVISIBLE (-2165 3960);
FORCEPROP 1 LAST HDL_POWER P3V3_AUX
J 1
(-2175 4050);
DISPLAY 0.872340 (-2175 4050);
PAINT GREEN (-2175 4050);
FORCEPROP 2 LAST CDS_LIB logical_power
J 0
(-2175 4000);
PAINT MONO (-2175 4000);
DISPLAY INVISIBLE (-2175 4000);
FORCEPROP 1 LAST PATH I19
J 0
(-2125 4025);
DISPLAY 0.872340 (-2125 4025);
PAINT AQUA (-2125 4025);
DISPLAY INVISIBLE (-2125 4025);
FORCEADD OFFPAGE..2
(-500 3275);
FORCEPROP 2 LAST $XR0 14 
J 0
(-311 3275);
DISPLAY 0.638298 (-311 3275);
PAINT MONO (-311 3275);
FORCEPROP 2 LAST CDS_LIB standard
J 0
(-500 3275);
PAINT MONO (-500 3275);
DISPLAY INVISIBLE (-500 3275);
FORCEPROP 1 LAST OFFPAGE TRUE
J 0
(-175 3150);
DISPLAY 0.872340 (-175 3150);
DISPLAY INVISIBLE (-175 3150);
FORCEPROP 1 LAST COMMENT_BODY TRUE
J 0
(-545 3180);
DISPLAY 0.872340 (-545 3180);
PAINT GREEN (-545 3180);
DISPLAY INVISIBLE (-545 3180);
FORCEPROP 2 LAST PATH I2
J 0
(-300 3325);
DISPLAY 1.021277 (-300 3325);
DISPLAY INVISIBLE (-300 3325);
FORCEADD Q_RES..2
(-2175 3625);
FORCEPROP 1 LAST PART_NUMBER CS21002FB06
J 0
(-2135 3500);
DISPLAY 0.510638 (-2135 3500);
DISPLAY INVISIBLE (-2135 3500);
FORCEPROP 1 LAST PACK_TYPE 0402LF
J 0
(-2135 3500);
DISPLAY 0.638298 (-2135 3500);
FORCEPROP 1 LAST VALUE 1K
J 0
(-2130 3700);
DISPLAY 0.638298 (-2130 3700);
FORCEPROP 1 LAST WATTAGE 1/16W
J 0
(-2135 3600);
DISPLAY 0.638298 (-2135 3600);
FORCEPROP 1 LAST TOLERANCE 1%
J 0
(-2130 3650);
DISPLAY 0.638298 (-2130 3650);
FORCEPROP 1 LAST MATERIAL EMPTY
J 0
(-2135 3550);
DISPLAY 0.638298 (-2135 3550);
PAINT RED (-2135 3550);
FORCEPROP 1 LAST $LOCATION R331
J 0
(-2130 3750);
DISPLAY 0.978723 (-2130 3750);
FORCEPROP 1 LASTPIN (-2175 3725) $PN 1
J 0
(-2170 3687);
DISPLAY 0.787234 (-2170 3687);
FORCEPROP 1 LASTPIN (-2175 3525) $PN 2
J 0
(-2170 3535);
DISPLAY 0.787234 (-2170 3535);
FORCEPROP 2 LAST CDS_LIB pure_quanta
J 0
(-2175 3625);
PAINT MONO (-2175 3625);
DISPLAY INVISIBLE (-2175 3625);
FORCEPROP 1 LAST PATH I20
J 0
(-2125 3800);
DISPLAY 0.978723 (-2125 3800);
PAINT WHITE (-2125 3800);
DISPLAY INVISIBLE (-2125 3800);
FORCEPROP 2 LAST CDS_LOCATION R331
J 0
(-2125 3850);
DISPLAY 1.021277 (-2125 3850);
DISPLAY INVISIBLE (-2125 3850);
FORCEPROP 2 LAST $SEC 1
J 0
(-2125 3850);
DISPLAY 0.680851 (-2125 3850);
PAINT MONO (-2125 3850);
DISPLAY INVISIBLE (-2125 3850);
FORCEPROP 2 LAST CDS_SEC 1
J 0
(-2125 3850);
DISPLAY 1.021277 (-2125 3850);
DISPLAY INVISIBLE (-2125 3850);
FORCEADD Q_RES..2
(-2175 2975);
FORCEPROP 1 LAST PART_NUMBER CS31002FB08
J 0
(-2135 2850);
DISPLAY 0.510638 (-2135 2850);
DISPLAY INVISIBLE (-2135 2850);
FORCEPROP 1 LAST WATTAGE 1/16W
J 0
(-2135 2950);
DISPLAY 0.638298 (-2135 2950);
FORCEPROP 1 LAST MATERIAL CHIP
J 0
(-2135 2900);
DISPLAY 0.638298 (-2135 2900);
FORCEPROP 1 LAST VALUE 10K
J 0
(-2130 3050);
DISPLAY 0.638298 (-2130 3050);
FORCEPROP 1 LAST TOLERANCE 1%
J 0
(-2130 3000);
DISPLAY 0.638298 (-2130 3000);
FORCEPROP 1 LAST PACK_TYPE 0402LF
J 0
(-2135 2850);
DISPLAY 0.638298 (-2135 2850);
FORCEPROP 1 LAST $LOCATION R332
J 0
(-2130 3100);
DISPLAY 0.978723 (-2130 3100);
FORCEPROP 1 LASTPIN (-2175 3075) $PN 1
J 0
(-2170 3037);
DISPLAY 0.787234 (-2170 3037);
FORCEPROP 1 LASTPIN (-2175 2875) $PN 2
J 0
(-2170 2885);
DISPLAY 0.787234 (-2170 2885);
FORCEPROP 2 LAST CDS_LIB pure_quanta
J 0
(-2175 2975);
PAINT MONO (-2175 2975);
DISPLAY INVISIBLE (-2175 2975);
FORCEPROP 1 LAST PATH I21
J 0
(-2125 3150);
DISPLAY 0.978723 (-2125 3150);
PAINT WHITE (-2125 3150);
DISPLAY INVISIBLE (-2125 3150);
FORCEPROP 2 LAST CDS_LOCATION R332
J 0
(-2125 3200);
DISPLAY 1.021277 (-2125 3200);
DISPLAY INVISIBLE (-2125 3200);
FORCEPROP 2 LAST $SEC 1
J 0
(-2125 3200);
DISPLAY 0.680851 (-2125 3200);
PAINT MONO (-2125 3200);
DISPLAY INVISIBLE (-2125 3200);
FORCEPROP 2 LAST CDS_SEC 1
J 0
(-2125 3200);
DISPLAY 1.021277 (-2125 3200);
DISPLAY INVISIBLE (-2125 3200);
FORCEADD UNIVERSAL_GND..1
(-2175 2750);
FORCEPROP 3 LASTPIN (-2175 2800) SIG_NAME GND\g
J 0
(-2165 2810);
DISPLAY 0.659574 (-2165 2810);
PAINT MONO (-2165 2810);
DISPLAY INVISIBLE (-2165 2810);
FORCEPROP 2 LAST CDS_LIB logical_power
J 0
(-2175 2750);
PAINT MONO (-2175 2750);
DISPLAY INVISIBLE (-2175 2750);
FORCEPROP 1 LAST HDL_POWER GND
J 1
(-2150 2675);
DISPLAY 0.872340 (-2150 2675);
PAINT GREEN (-2150 2675);
DISPLAY INVISIBLE (-2150 2675);
FORCEPROP 1 LAST PATH I22
J 0
(-2100 2750);
DISPLAY 0.872340 (-2100 2750);
PAINT AQUA (-2100 2750);
DISPLAY INVISIBLE (-2100 2750);
FORCEADD UNIVERSAL_POWER..1
(1075 3975);
FORCEPROP 3 LASTPIN (1075 3925) SIG_NAME P3V3_AUX\g
J 0
(1085 3935);
DISPLAY 0.659574 (1085 3935);
PAINT MONO (1085 3935);
DISPLAY INVISIBLE (1085 3935);
FORCEPROP 1 LAST HDL_POWER P3V3_AUX
J 1
(1075 4025);
DISPLAY 0.872340 (1075 4025);
PAINT GREEN (1075 4025);
FORCEPROP 2 LAST CDS_LIB logical_power
J 0
(1075 3975);
PAINT MONO (1075 3975);
DISPLAY INVISIBLE (1075 3975);
FORCEPROP 1 LAST PATH I23
J 0
(1125 4000);
DISPLAY 0.872340 (1125 4000);
PAINT AQUA (1125 4000);
DISPLAY INVISIBLE (1125 4000);
FORCEADD Q_RES..2
(1075 3625);
FORCEPROP 1 LAST PART_NUMBER CS21002FB06
J 0
(1115 3500);
DISPLAY 0.510638 (1115 3500);
DISPLAY INVISIBLE (1115 3500);
FORCEPROP 1 LAST MATERIAL EMPTY
J 0
(1115 3550);
DISPLAY 0.638298 (1115 3550);
PAINT RED (1115 3550);
FORCEPROP 1 LAST TOLERANCE 1%
J 0
(1120 3650);
DISPLAY 0.638298 (1120 3650);
FORCEPROP 1 LAST WATTAGE 1/16W
J 0
(1115 3600);
DISPLAY 0.638298 (1115 3600);
FORCEPROP 1 LAST PACK_TYPE 0402LF
J 0
(1115 3500);
DISPLAY 0.638298 (1115 3500);
FORCEPROP 1 LAST VALUE 1K
J 0
(1120 3700);
DISPLAY 0.638298 (1120 3700);
FORCEPROP 1 LAST $LOCATION R625
J 0
(1120 3750);
DISPLAY 0.978723 (1120 3750);
FORCEPROP 1 LASTPIN (1075 3725) $PN 1
J 0
(1080 3687);
DISPLAY 0.787234 (1080 3687);
FORCEPROP 1 LASTPIN (1075 3525) $PN 2
J 0
(1080 3535);
DISPLAY 0.787234 (1080 3535);
FORCEPROP 2 LAST CDS_LIB pure_quanta
J 0
(1075 3625);
PAINT MONO (1075 3625);
DISPLAY INVISIBLE (1075 3625);
FORCEPROP 1 LAST PATH I24
J 0
(1125 3800);
DISPLAY 0.978723 (1125 3800);
PAINT WHITE (1125 3800);
DISPLAY INVISIBLE (1125 3800);
FORCEPROP 2 LAST CDS_LOCATION R625
J 0
(1125 3850);
DISPLAY 1.021277 (1125 3850);
DISPLAY INVISIBLE (1125 3850);
FORCEPROP 2 LAST $SEC 1
J 0
(1125 3850);
DISPLAY 0.680851 (1125 3850);
PAINT MONO (1125 3850);
DISPLAY INVISIBLE (1125 3850);
FORCEPROP 2 LAST CDS_SEC 1
J 0
(1125 3850);
DISPLAY 1.021277 (1125 3850);
DISPLAY INVISIBLE (1125 3850);
FORCEADD UNIVERSAL_GND..1
(1075 2750);
FORCEPROP 3 LASTPIN (1075 2800) SIG_NAME GND\g
J 0
(1085 2810);
DISPLAY 0.659574 (1085 2810);
PAINT MONO (1085 2810);
DISPLAY INVISIBLE (1085 2810);
FORCEPROP 2 LAST CDS_LIB logical_power
J 0
(1075 2750);
PAINT MONO (1075 2750);
DISPLAY INVISIBLE (1075 2750);
FORCEPROP 1 LAST HDL_POWER GND
J 1
(1100 2675);
DISPLAY 0.872340 (1100 2675);
PAINT GREEN (1100 2675);
DISPLAY INVISIBLE (1100 2675);
FORCEPROP 1 LAST PATH I25
J 0
(1150 2750);
DISPLAY 0.872340 (1150 2750);
PAINT AQUA (1150 2750);
DISPLAY INVISIBLE (1150 2750);
FORCEADD Q_RES..2
(1075 2975);
FORCEPROP 1 LAST PART_NUMBER CS31002FB08
J 0
(1115 2850);
DISPLAY 0.510638 (1115 2850);
DISPLAY INVISIBLE (1115 2850);
FORCEPROP 1 LAST MATERIAL CHIP
J 0
(1115 2900);
DISPLAY 0.638298 (1115 2900);
FORCEPROP 1 LAST WATTAGE 1/16W
J 0
(1115 2950);
DISPLAY 0.638298 (1115 2950);
FORCEPROP 1 LAST TOLERANCE 1%
J 0
(1120 3000);
DISPLAY 0.638298 (1120 3000);
FORCEPROP 1 LAST VALUE 10K
J 0
(1120 3050);
DISPLAY 0.638298 (1120 3050);
FORCEPROP 1 LAST PACK_TYPE 0402LF
J 0
(1115 2850);
DISPLAY 0.638298 (1115 2850);
FORCEPROP 1 LAST $LOCATION R626
J 0
(1120 3100);
DISPLAY 0.978723 (1120 3100);
FORCEPROP 1 LASTPIN (1075 3075) $PN 1
J 0
(1080 3037);
DISPLAY 0.787234 (1080 3037);
FORCEPROP 1 LASTPIN (1075 2875) $PN 2
J 0
(1080 2885);
DISPLAY 0.787234 (1080 2885);
FORCEPROP 2 LAST CDS_LIB pure_quanta
J 0
(1075 2975);
PAINT MONO (1075 2975);
DISPLAY INVISIBLE (1075 2975);
FORCEPROP 1 LAST PATH I26
J 0
(1125 3150);
DISPLAY 0.978723 (1125 3150);
PAINT WHITE (1125 3150);
DISPLAY INVISIBLE (1125 3150);
FORCEPROP 2 LAST CDS_LOCATION R626
J 0
(1125 3200);
DISPLAY 1.021277 (1125 3200);
DISPLAY INVISIBLE (1125 3200);
FORCEPROP 2 LAST $SEC 1
J 0
(1125 3200);
DISPLAY 0.680851 (1125 3200);
PAINT MONO (1125 3200);
DISPLAY INVISIBLE (1125 3200);
FORCEPROP 2 LAST CDS_SEC 1
J 0
(1125 3200);
DISPLAY 1.021277 (1125 3200);
DISPLAY INVISIBLE (1125 3200);
FORCEADD OFFPAGE..2
(-500 1725);
FORCEPROP 2 LAST $XR0 14 
J 0
(-311 1725);
DISPLAY 0.638298 (-311 1725);
PAINT MONO (-311 1725);
FORCEPROP 2 LAST CDS_LIB standard
J 0
(-500 1725);
PAINT MONO (-500 1725);
DISPLAY INVISIBLE (-500 1725);
FORCEPROP 1 LAST OFFPAGE TRUE
J 0
(-175 1600);
DISPLAY 0.872340 (-175 1600);
DISPLAY INVISIBLE (-175 1600);
FORCEPROP 1 LAST COMMENT_BODY TRUE
J 0
(-545 1630);
DISPLAY 0.872340 (-545 1630);
PAINT GREEN (-545 1630);
DISPLAY INVISIBLE (-545 1630);
FORCEPROP 2 LAST PATH I27
J 0
(-300 1775);
DISPLAY 1.021277 (-300 1775);
DISPLAY INVISIBLE (-300 1775);
FORCEADD UNIVERSAL_POWER..1
(-2175 2300);
FORCEPROP 3 LASTPIN (-2175 2250) SIG_NAME P3V3_AUX\g
J 0
(-2165 2260);
DISPLAY 0.659574 (-2165 2260);
PAINT MONO (-2165 2260);
DISPLAY INVISIBLE (-2165 2260);
FORCEPROP 1 LAST HDL_POWER P3V3_AUX
J 1
(-2175 2350);
DISPLAY 0.872340 (-2175 2350);
PAINT GREEN (-2175 2350);
FORCEPROP 2 LAST CDS_LIB logical_power
J 0
(-2175 2300);
PAINT MONO (-2175 2300);
DISPLAY INVISIBLE (-2175 2300);
FORCEPROP 1 LAST PATH I28
J 0
(-2125 2325);
DISPLAY 0.872340 (-2125 2325);
PAINT AQUA (-2125 2325);
DISPLAY INVISIBLE (-2125 2325);
FORCEADD OFFPAGE..2
(-500 3350);
FORCEPROP 2 LAST $XR0 14 
J 0
(-311 3350);
DISPLAY 0.638298 (-311 3350);
PAINT MONO (-311 3350);
FORCEPROP 2 LAST CDS_LIB standard
J 0
(-500 3350);
PAINT MONO (-500 3350);
DISPLAY INVISIBLE (-500 3350);
FORCEPROP 1 LAST OFFPAGE TRUE
J 0
(-175 3225);
DISPLAY 0.872340 (-175 3225);
DISPLAY INVISIBLE (-175 3225);
FORCEPROP 1 LAST COMMENT_BODY TRUE
J 0
(-545 3255);
DISPLAY 0.872340 (-545 3255);
PAINT GREEN (-545 3255);
DISPLAY INVISIBLE (-545 3255);
FORCEPROP 2 LAST PATH I3
J 0
(-300 3400);
DISPLAY 1.021277 (-300 3400);
DISPLAY INVISIBLE (-300 3400);
FORCEADD UNIVERSAL_GND..1
(-2175 1250);
FORCEPROP 3 LASTPIN (-2175 1300) SIG_NAME GND\g
J 0
(-2165 1310);
DISPLAY 0.659574 (-2165 1310);
PAINT MONO (-2165 1310);
DISPLAY INVISIBLE (-2165 1310);
FORCEPROP 2 LAST CDS_LIB logical_power
J 0
(-2175 1250);
PAINT MONO (-2175 1250);
DISPLAY INVISIBLE (-2175 1250);
FORCEPROP 1 LAST HDL_POWER GND
J 1
(-2150 1175);
DISPLAY 0.872340 (-2150 1175);
PAINT GREEN (-2150 1175);
DISPLAY INVISIBLE (-2150 1175);
FORCEPROP 1 LAST PATH I30
J 0
(-2100 1250);
DISPLAY 0.872340 (-2100 1250);
PAINT AQUA (-2100 1250);
DISPLAY INVISIBLE (-2100 1250);
FORCEADD Q_RES..2
(-2175 1475);
FORCEPROP 1 LAST PART_NUMBER CS31002FB08
J 0
(-2135 1350);
DISPLAY 0.510638 (-2135 1350);
DISPLAY INVISIBLE (-2135 1350);
FORCEPROP 1 LAST WATTAGE 1/16W
J 0
(-2135 1450);
DISPLAY 0.638298 (-2135 1450);
FORCEPROP 1 LAST PACK_TYPE 0402LF
J 0
(-2135 1300);
DISPLAY 0.638298 (-2135 1300);
FORCEPROP 1 LAST TOLERANCE 1%
J 0
(-2130 1500);
DISPLAY 0.638298 (-2130 1500);
FORCEPROP 1 LAST VALUE 10K
J 0
(-2130 1550);
DISPLAY 0.638298 (-2130 1550);
FORCEPROP 1 LAST MATERIAL EMPTY
J 0
(-2135 1400);
DISPLAY 0.638298 (-2135 1400);
PAINT RED (-2135 1400);
FORCEPROP 1 LAST $LOCATION R997
J 0
(-2130 1600);
DISPLAY 0.978723 (-2130 1600);
FORCEPROP 1 LASTPIN (-2175 1575) $PN 1
J 0
(-2170 1537);
DISPLAY 0.787234 (-2170 1537);
FORCEPROP 1 LASTPIN (-2175 1375) $PN 2
J 0
(-2170 1385);
DISPLAY 0.787234 (-2170 1385);
FORCEPROP 2 LAST CDS_LIB pure_quanta
J 0
(-2175 1475);
PAINT MONO (-2175 1475);
DISPLAY INVISIBLE (-2175 1475);
FORCEPROP 1 LAST PATH I31
J 0
(-2125 1650);
DISPLAY 0.978723 (-2125 1650);
PAINT WHITE (-2125 1650);
DISPLAY INVISIBLE (-2125 1650);
FORCEPROP 2 LAST CDS_LOCATION R997
J 0
(-2125 1700);
DISPLAY 1.021277 (-2125 1700);
DISPLAY INVISIBLE (-2125 1700);
FORCEPROP 2 LAST $SEC 1
J 0
(-2125 1700);
DISPLAY 0.680851 (-2125 1700);
PAINT MONO (-2125 1700);
DISPLAY INVISIBLE (-2125 1700);
FORCEPROP 2 LAST CDS_SEC 1
J 0
(-2125 1700);
DISPLAY 1.021277 (-2125 1700);
DISPLAY INVISIBLE (-2125 1700);
FORCEADD Q_RES..2
(-2175 2000);
FORCEPROP 1 LAST PART_NUMBER CS21002FB06
J 0
(-2135 1875);
DISPLAY 0.638298 (-2135 1875);
DISPLAY INVISIBLE (-2135 1875);
FORCEPROP 1 LAST PACK_TYPE 0402LF
J 0
(-2135 1825);
DISPLAY 0.638298 (-2135 1825);
FORCEPROP 1 LAST VALUE 1K
J 0
(-2130 2075);
DISPLAY 0.638298 (-2130 2075);
FORCEPROP 1 LAST WATTAGE 1/16W
J 0
(-2135 1975);
DISPLAY 0.638298 (-2135 1975);
FORCEPROP 1 LAST TOLERANCE 1%
J 0
(-2130 2025);
DISPLAY 0.638298 (-2130 2025);
FORCEPROP 1 LAST MATERIAL CHIP
J 0
(-2135 1925);
DISPLAY 0.638298 (-2135 1925);
FORCEPROP 1 LAST $LOCATION R650
J 0
(-2130 2125);
DISPLAY 0.978723 (-2130 2125);
FORCEPROP 1 LASTPIN (-2175 2100) $PN 1
J 0
(-2170 2062);
DISPLAY 0.787234 (-2170 2062);
FORCEPROP 1 LASTPIN (-2175 1900) $PN 2
J 0
(-2170 1910);
DISPLAY 0.787234 (-2170 1910);
FORCEPROP 2 LAST CDS_LIB pure_quanta
J 0
(-2175 2000);
PAINT MONO (-2175 2000);
DISPLAY INVISIBLE (-2175 2000);
FORCEPROP 1 LAST PATH I32
J 0
(-2125 2175);
DISPLAY 0.978723 (-2125 2175);
PAINT WHITE (-2125 2175);
DISPLAY INVISIBLE (-2125 2175);
FORCEPROP 2 LAST CDS_LOCATION R650
J 0
(-2125 2225);
DISPLAY 1.021277 (-2125 2225);
DISPLAY INVISIBLE (-2125 2225);
FORCEPROP 2 LAST $SEC 1
J 0
(-2125 2225);
DISPLAY 0.680851 (-2125 2225);
PAINT MONO (-2125 2225);
DISPLAY INVISIBLE (-2125 2225);
FORCEPROP 2 LAST CDS_SEC 1
J 0
(-2125 2225);
DISPLAY 1.021277 (-2125 2225);
DISPLAY INVISIBLE (-2125 2225);
FORCEADD OFFPAGE..2
(2750 1725);
FORCEPROP 2 LAST $XR0 45 
J 0
(2939 1725);
DISPLAY 0.638298 (2939 1725);
PAINT MONO (2939 1725);
FORCEPROP 2 LAST CDS_LIB standard
J 0
(2750 1725);
PAINT MONO (2750 1725);
DISPLAY INVISIBLE (2750 1725);
FORCEPROP 1 LAST OFFPAGE TRUE
J 0
(3075 1600);
DISPLAY 0.872340 (3075 1600);
DISPLAY INVISIBLE (3075 1600);
FORCEPROP 1 LAST COMMENT_BODY TRUE
J 0
(2705 1630);
DISPLAY 0.872340 (2705 1630);
PAINT GREEN (2705 1630);
DISPLAY INVISIBLE (2705 1630);
FORCEPROP 2 LAST PATH I33
J 0
(2950 1775);
DISPLAY 1.021277 (2950 1775);
DISPLAY INVISIBLE (2950 1775);
FORCEADD UNIVERSAL_POWER..1
(1075 2300);
FORCEPROP 3 LASTPIN (1075 2250) SIG_NAME P3V3_AUX\g
J 0
(1085 2260);
DISPLAY 0.659574 (1085 2260);
PAINT MONO (1085 2260);
DISPLAY INVISIBLE (1085 2260);
FORCEPROP 1 LAST HDL_POWER P3V3_AUX
J 1
(1075 2350);
DISPLAY 0.872340 (1075 2350);
PAINT GREEN (1075 2350);
FORCEPROP 2 LAST CDS_LIB logical_power
J 0
(1075 2300);
PAINT MONO (1075 2300);
DISPLAY INVISIBLE (1075 2300);
FORCEPROP 1 LAST PATH I34
J 0
(1125 2325);
DISPLAY 0.872340 (1125 2325);
PAINT AQUA (1125 2325);
DISPLAY INVISIBLE (1125 2325);
FORCEADD Q_RES..2
(1075 2000);
FORCEPROP 1 LAST PART_NUMBER CS21002FB06
J 0
(1115 1875);
DISPLAY 0.638298 (1115 1875);
DISPLAY INVISIBLE (1115 1875);
FORCEPROP 1 LAST PACK_TYPE 0402LF
J 0
(1115 1825);
DISPLAY 0.638298 (1115 1825);
FORCEPROP 1 LAST TOLERANCE 1%
J 0
(1120 2025);
DISPLAY 0.638298 (1120 2025);
FORCEPROP 1 LAST WATTAGE 1/16W
J 0
(1115 1975);
DISPLAY 0.638298 (1115 1975);
FORCEPROP 1 LAST VALUE 1K
J 0
(1120 2075);
DISPLAY 0.638298 (1120 2075);
FORCEPROP 1 LAST MATERIAL CHIP
J 0
(1115 1925);
DISPLAY 0.638298 (1115 1925);
FORCEPROP 1 LAST $LOCATION R1004
J 0
(1120 2125);
DISPLAY 0.978723 (1120 2125);
FORCEPROP 1 LASTPIN (1075 2100) $PN 1
J 0
(1080 2062);
DISPLAY 0.787234 (1080 2062);
FORCEPROP 1 LASTPIN (1075 1900) $PN 2
J 0
(1080 1910);
DISPLAY 0.787234 (1080 1910);
FORCEPROP 2 LAST CDS_LIB pure_quanta
J 0
(1075 2000);
PAINT MONO (1075 2000);
DISPLAY INVISIBLE (1075 2000);
FORCEPROP 1 LAST PATH I35
J 0
(1125 2175);
DISPLAY 0.978723 (1125 2175);
PAINT WHITE (1125 2175);
DISPLAY INVISIBLE (1125 2175);
FORCEPROP 2 LAST CDS_LOCATION R1004
J 0
(1125 2225);
DISPLAY 1.021277 (1125 2225);
DISPLAY INVISIBLE (1125 2225);
FORCEPROP 2 LAST $SEC 1
J 0
(1125 2225);
DISPLAY 0.680851 (1125 2225);
PAINT MONO (1125 2225);
DISPLAY INVISIBLE (1125 2225);
FORCEPROP 2 LAST CDS_SEC 1
J 0
(1125 2225);
DISPLAY 1.021277 (1125 2225);
DISPLAY INVISIBLE (1125 2225);
FORCEADD Q_RES..2
(1075 1475);
FORCEPROP 1 LAST PART_NUMBER CS31002FB08
J 0
(1115 1350);
DISPLAY 0.510638 (1115 1350);
DISPLAY INVISIBLE (1115 1350);
FORCEPROP 1 LAST VALUE 10K
J 0
(1120 1550);
DISPLAY 0.638298 (1120 1550);
FORCEPROP 1 LAST WATTAGE 1/16W
J 0
(1115 1450);
DISPLAY 0.638298 (1115 1450);
FORCEPROP 1 LAST TOLERANCE 1%
J 0
(1120 1500);
DISPLAY 0.638298 (1120 1500);
FORCEPROP 1 LAST PACK_TYPE 0402LF
J 0
(1115 1300);
DISPLAY 0.638298 (1115 1300);
FORCEPROP 1 LAST MATERIAL EMPTY
J 0
(1115 1400);
DISPLAY 0.638298 (1115 1400);
PAINT RED (1115 1400);
FORCEPROP 1 LAST $LOCATION R1005
J 0
(1120 1600);
DISPLAY 0.978723 (1120 1600);
FORCEPROP 1 LASTPIN (1075 1575) $PN 1
J 0
(1080 1537);
DISPLAY 0.787234 (1080 1537);
FORCEPROP 1 LASTPIN (1075 1375) $PN 2
J 0
(1080 1385);
DISPLAY 0.787234 (1080 1385);
FORCEPROP 2 LAST CDS_LIB pure_quanta
J 0
(1075 1475);
PAINT MONO (1075 1475);
DISPLAY INVISIBLE (1075 1475);
FORCEPROP 1 LAST PATH I36
J 0
(1125 1650);
DISPLAY 0.978723 (1125 1650);
PAINT WHITE (1125 1650);
DISPLAY INVISIBLE (1125 1650);
FORCEPROP 2 LAST CDS_LOCATION R1005
J 0
(1125 1700);
DISPLAY 1.021277 (1125 1700);
DISPLAY INVISIBLE (1125 1700);
FORCEPROP 2 LAST $SEC 1
J 0
(1125 1700);
DISPLAY 0.680851 (1125 1700);
PAINT MONO (1125 1700);
DISPLAY INVISIBLE (1125 1700);
FORCEPROP 2 LAST CDS_SEC 1
J 0
(1125 1700);
DISPLAY 1.021277 (1125 1700);
DISPLAY INVISIBLE (1125 1700);
FORCEADD UNIVERSAL_GND..1
(1075 1250);
FORCEPROP 3 LASTPIN (1075 1300) SIG_NAME GND\g
J 0
(1085 1310);
DISPLAY 0.659574 (1085 1310);
PAINT MONO (1085 1310);
DISPLAY INVISIBLE (1085 1310);
FORCEPROP 2 LAST CDS_LIB logical_power
J 0
(1075 1250);
PAINT MONO (1075 1250);
DISPLAY INVISIBLE (1075 1250);
FORCEPROP 1 LAST HDL_POWER GND
J 1
(1100 1175);
DISPLAY 0.872340 (1100 1175);
PAINT GREEN (1100 1175);
DISPLAY INVISIBLE (1100 1175);
FORCEPROP 1 LAST PATH I37
J 0
(1150 1250);
DISPLAY 0.872340 (1150 1250);
PAINT AQUA (1150 1250);
DISPLAY INVISIBLE (1150 1250);
FORCEADD OFFPAGE..2
(-500 3200);
FORCEPROP 2 LAST $XR0 14 
J 0
(-311 3200);
DISPLAY 0.638298 (-311 3200);
PAINT MONO (-311 3200);
FORCEPROP 2 LAST CDS_LIB standard
J 0
(-500 3200);
PAINT MONO (-500 3200);
DISPLAY INVISIBLE (-500 3200);
FORCEPROP 1 LAST OFFPAGE TRUE
J 0
(-175 3075);
DISPLAY 0.872340 (-175 3075);
DISPLAY INVISIBLE (-175 3075);
FORCEPROP 1 LAST COMMENT_BODY TRUE
J 0
(-545 3105);
DISPLAY 0.872340 (-545 3105);
PAINT GREEN (-545 3105);
DISPLAY INVISIBLE (-545 3105);
FORCEPROP 2 LAST PATH I4
J 0
(-300 3250);
DISPLAY 1.021277 (-300 3250);
DISPLAY INVISIBLE (-300 3250);
FORCEADD Q_RES..2
(-1625 3625);
FORCEPROP 1 LAST PART_NUMBER CS21002FB06
J 0
(-1585 3500);
DISPLAY 0.510638 (-1585 3500);
DISPLAY INVISIBLE (-1585 3500);
FORCEPROP 1 LAST VALUE 1K
J 0
(-1580 3700);
DISPLAY 0.638298 (-1580 3700);
FORCEPROP 1 LAST TOLERANCE 1%
J 0
(-1580 3650);
DISPLAY 0.638298 (-1580 3650);
FORCEPROP 1 LAST WATTAGE 1/16W
J 0
(-1585 3600);
DISPLAY 0.638298 (-1585 3600);
FORCEPROP 1 LAST PACK_TYPE 0402LF
J 0
(-1585 3450);
DISPLAY 0.638298 (-1585 3450);
FORCEPROP 1 LAST MATERIAL EMPTY
J 0
(-1585 3550);
DISPLAY 0.638298 (-1585 3550);
PAINT RED (-1585 3550);
FORCEPROP 1 LAST $LOCATION R335
J 0
(-1580 3750);
DISPLAY 0.978723 (-1580 3750);
FORCEPROP 1 LASTPIN (-1625 3725) $PN 1
J 0
(-1620 3687);
DISPLAY 0.787234 (-1620 3687);
FORCEPROP 1 LASTPIN (-1625 3525) $PN 2
J 0
(-1620 3535);
DISPLAY 0.787234 (-1620 3535);
FORCEPROP 2 LAST CDS_LIB pure_quanta
J 0
(-1625 3625);
PAINT MONO (-1625 3625);
DISPLAY INVISIBLE (-1625 3625);
FORCEPROP 1 LAST PATH I5
J 0
(-1575 3800);
DISPLAY 0.978723 (-1575 3800);
PAINT WHITE (-1575 3800);
DISPLAY INVISIBLE (-1575 3800);
FORCEPROP 2 LAST CDS_LOCATION R335
J 0
(-1575 3850);
DISPLAY 1.021277 (-1575 3850);
DISPLAY INVISIBLE (-1575 3850);
FORCEPROP 2 LAST $SEC 1
J 0
(-1575 3850);
DISPLAY 0.680851 (-1575 3850);
PAINT MONO (-1575 3850);
DISPLAY INVISIBLE (-1575 3850);
FORCEPROP 2 LAST CDS_SEC 1
J 0
(-1575 3850);
DISPLAY 1.021277 (-1575 3850);
DISPLAY INVISIBLE (-1575 3850);
FORCEADD Q_RES..2
(-1900 3625);
FORCEPROP 1 LAST PART_NUMBER CS21002FB06
J 0
(-1860 3500);
DISPLAY 0.510638 (-1860 3500);
DISPLAY INVISIBLE (-1860 3500);
FORCEPROP 1 LAST VALUE 1K
J 0
(-1855 3700);
DISPLAY 0.638298 (-1855 3700);
FORCEPROP 1 LAST MATERIAL EMPTY
J 0
(-1860 3550);
DISPLAY 0.638298 (-1860 3550);
PAINT RED (-1860 3550);
FORCEPROP 1 LAST TOLERANCE 1%
J 0
(-1855 3650);
DISPLAY 0.638298 (-1855 3650);
FORCEPROP 1 LAST WATTAGE 1/16W
J 0
(-1860 3600);
DISPLAY 0.638298 (-1860 3600);
FORCEPROP 1 LAST PACK_TYPE 0402LF
J 0
(-1860 3500);
DISPLAY 0.638298 (-1860 3500);
FORCEPROP 1 LAST $LOCATION R333
J 0
(-1855 3750);
DISPLAY 0.978723 (-1855 3750);
FORCEPROP 1 LASTPIN (-1900 3725) $PN 1
J 0
(-1895 3687);
DISPLAY 0.787234 (-1895 3687);
FORCEPROP 1 LASTPIN (-1900 3525) $PN 2
J 0
(-1895 3535);
DISPLAY 0.787234 (-1895 3535);
FORCEPROP 2 LAST CDS_LIB pure_quanta
J 0
(-1900 3625);
PAINT MONO (-1900 3625);
DISPLAY INVISIBLE (-1900 3625);
FORCEPROP 1 LAST PATH I6
J 0
(-1850 3800);
DISPLAY 0.978723 (-1850 3800);
PAINT WHITE (-1850 3800);
DISPLAY INVISIBLE (-1850 3800);
FORCEPROP 2 LAST CDS_LOCATION R333
J 0
(-1850 3850);
DISPLAY 1.021277 (-1850 3850);
DISPLAY INVISIBLE (-1850 3850);
FORCEPROP 2 LAST $SEC 1
J 0
(-1850 3850);
DISPLAY 0.680851 (-1850 3850);
PAINT MONO (-1850 3850);
DISPLAY INVISIBLE (-1850 3850);
FORCEPROP 2 LAST CDS_SEC 1
J 0
(-1850 3850);
DISPLAY 1.021277 (-1850 3850);
DISPLAY INVISIBLE (-1850 3850);
FORCEADD Q_RES..2
(-1625 2975);
FORCEPROP 1 LAST PART_NUMBER CS31002FB08
J 0
(-1585 2850);
DISPLAY 0.510638 (-1585 2850);
DISPLAY INVISIBLE (-1585 2850);
FORCEPROP 1 LAST PACK_TYPE 0402LF
J 0
(-1585 2800);
DISPLAY 0.638298 (-1585 2800);
FORCEPROP 1 LAST TOLERANCE 1%
J 0
(-1580 3000);
DISPLAY 0.638298 (-1580 3000);
FORCEPROP 1 LAST WATTAGE 1/16W
J 0
(-1585 2950);
DISPLAY 0.638298 (-1585 2950);
FORCEPROP 1 LAST MATERIAL CHIP
J 0
(-1585 2900);
DISPLAY 0.638298 (-1585 2900);
FORCEPROP 1 LAST VALUE 10K
J 0
(-1580 3050);
DISPLAY 0.638298 (-1580 3050);
FORCEPROP 1 LAST $LOCATION R515
J 0
(-1580 3100);
DISPLAY 0.978723 (-1580 3100);
FORCEPROP 1 LASTPIN (-1625 3075) $PN 1
J 0
(-1620 3037);
DISPLAY 0.787234 (-1620 3037);
FORCEPROP 1 LASTPIN (-1625 2875) $PN 2
J 0
(-1620 2885);
DISPLAY 0.787234 (-1620 2885);
FORCEPROP 2 LAST CDS_LIB pure_quanta
J 0
(-1625 2975);
PAINT MONO (-1625 2975);
DISPLAY INVISIBLE (-1625 2975);
FORCEPROP 1 LAST PATH I7
J 0
(-1575 3150);
DISPLAY 0.978723 (-1575 3150);
PAINT WHITE (-1575 3150);
DISPLAY INVISIBLE (-1575 3150);
FORCEPROP 2 LAST CDS_LOCATION R515
J 0
(-1575 3200);
DISPLAY 1.021277 (-1575 3200);
DISPLAY INVISIBLE (-1575 3200);
FORCEPROP 2 LAST $SEC 1
J 0
(-1575 3200);
DISPLAY 0.680851 (-1575 3200);
PAINT MONO (-1575 3200);
DISPLAY INVISIBLE (-1575 3200);
FORCEPROP 2 LAST CDS_SEC 1
J 0
(-1575 3200);
DISPLAY 1.021277 (-1575 3200);
DISPLAY INVISIBLE (-1575 3200);
FORCEADD UNIVERSAL_GND..1
(-1625 2750);
FORCEPROP 3 LASTPIN (-1625 2800) SIG_NAME GND\g
J 0
(-1615 2810);
DISPLAY 0.659574 (-1615 2810);
PAINT MONO (-1615 2810);
DISPLAY INVISIBLE (-1615 2810);
FORCEPROP 2 LAST CDS_LIB logical_power
J 0
(-1625 2750);
PAINT MONO (-1625 2750);
DISPLAY INVISIBLE (-1625 2750);
FORCEPROP 1 LAST HDL_POWER GND
J 1
(-1600 2675);
DISPLAY 0.872340 (-1600 2675);
PAINT GREEN (-1600 2675);
DISPLAY INVISIBLE (-1600 2675);
FORCEPROP 1 LAST PATH I8
J 0
(-1550 2750);
DISPLAY 0.872340 (-1550 2750);
PAINT AQUA (-1550 2750);
DISPLAY INVISIBLE (-1550 2750);
FORCEADD UNIVERSAL_GND..1
(-1900 2750);
FORCEPROP 3 LASTPIN (-1900 2800) SIG_NAME GND\g
J 0
(-1890 2810);
DISPLAY 0.659574 (-1890 2810);
PAINT MONO (-1890 2810);
DISPLAY INVISIBLE (-1890 2810);
FORCEPROP 2 LAST CDS_LIB logical_power
J 0
(-1900 2750);
PAINT MONO (-1900 2750);
DISPLAY INVISIBLE (-1900 2750);
FORCEPROP 1 LAST HDL_POWER GND
J 1
(-1875 2675);
DISPLAY 0.872340 (-1875 2675);
PAINT GREEN (-1875 2675);
DISPLAY INVISIBLE (-1875 2675);
FORCEPROP 1 LAST PATH I9
J 0
(-1825 2750);
DISPLAY 0.872340 (-1825 2750);
PAINT AQUA (-1825 2750);
DISPLAY INVISIBLE (-1825 2750);
FORCEADD QUANTA_TITLE_BLOCK_C..1
(5750 -2125);
FORCEPROP 0 LAST CDS_CON_LAST_MODIFIED Fri Aug 25 14:01:47 2023
J 0
(3865 -2110);
PAINT MONO (3865 -2110);
DISPLAY INVISIBLE (3865 -2110);
FORCEPROP 1 LAST CUSTOM_TXT_CDS <CON_LAST_MODIFIED>
J 0
(3865 -2110);
DISPLAY 0.978723 (3865 -2110);
FORCEPROP 2 LAST CUSTOM_TXT_CDS <XR_PAGE_TITLE>
J 0
(-2140 3125);
DISPLAY 0.638298 (-2140 3125);
PAINT PINK (-2140 3125);
DISPLAY INVISIBLE (-2140 3125);
FORCEPROP 1 LAST CUSTOM_TXT_CDS <NAME_2>
J 0
(2575 -2075);
FORCEPROP 1 LAST CUSTOM_TXT_CDS <NAME_1>
J 0
(2575 -1950);
FORCEPROP 1 LAST CUSTOM_TXT_CDS <Q_NUMBER>
J 0
(4347 -2022);
DISPLAY 1.212766 (4347 -2022);
FORCEPROP 1 LAST CUSTOM_TXT_CDS <Q_PROJ>
J 0
(3368 -2023);
DISPLAY 1.212766 (3368 -2023);
FORCEPROP 1 LAST CUSTOM_TXT_CDS <Q_REV>
J 0
(5566 -2022);
DISPLAY 1.212766 (5566 -2022);
FORCEPROP 1 LAST CUSTOM_TXT_CDS <CON_PAGE_NUM> OF <CON_TOTAL_PAGES>
J 0
(5304 -2107);
DISPLAY 0.978723 (5304 -2107);
FORCEPROP 1 LAST Q_TITLE SPR CPU0 & 1 - PIROM
J 0
(-3516 -2124);
DISPLAY 2.446809 (-3516 -2124);
PAINT GREEN (-3516 -2124);
FORCEPROP 1 LAST Q_DEPT 
J 1
(1987 -2076);
DISPLAY 1.957447 (1987 -2076);
PAINT GREEN (1987 -2076);
FORCEPROP 2 LAST CDS_XR_PAGE_TITLE CR-127 : @S9S_MB_2U_LIB.S9S_MB_2U(SCH_1):PAGE127
J 0
(-2140 3125);
DISPLAY 0.638298 (-2140 3125);
PAINT PINK (-2140 3125);
DISPLAY INVISIBLE (-2140 3125);
FORCEPROP 2 LAST CDS_LIB pure_quanta
J 0
(5750 -2125);
PAINT MONO (5750 -2125);
DISPLAY INVISIBLE (5750 -2125);
FORCEPROP 1 LAST CDS_LMAN_SYM_OUTLINE -9475,6775,100,-125
J 0
(5750 -2125);
DISPLAY 0.468085 (5750 -2125);
PAINT GREEN (5750 -2125);
DISPLAY INVISIBLE (5750 -2125);
FORCEPROP 2 LAST PAGE_BORDER TRUE
J 0
(-2140 3125);
DISPLAY 0.638298 (-2140 3125);
PAINT PINK (-2140 3125);
DISPLAY INVISIBLE (-2140 3125);
FORCEPROP 1 LAST COMMENT_BODY TRUE
J 0
(5762 -2138);
DISPLAY 0.978723 (5762 -2138);
PAINT GREEN (5762 -2138);
DISPLAY INVISIBLE (5762 -2138);
FORCEADD DNS..2
(1080 1445);
PAINT RED (1080 1445);
FORCEPROP 2 LAST CDS_LIB mstr_misc
J 0
(1080 1445);
PAINT MONO (1080 1445);
DISPLAY INVISIBLE (1080 1445);
FORCEPROP 1 LAST COMMENT_BODY TRUE
J 0
(1080 1445);
DISPLAY INVISIBLE (1080 1445);
FORCEADD DNS..2
(1355 3595);
PAINT RED (1355 3595);
FORCEPROP 2 LAST CDS_LIB mstr_misc
J 0
(1355 3595);
PAINT MONO (1355 3595);
DISPLAY INVISIBLE (1355 3595);
FORCEPROP 1 LAST COMMENT_BODY TRUE
J 0
(1355 3595);
DISPLAY INVISIBLE (1355 3595);
FORCEADD DNS..2
(1080 3595);
PAINT RED (1080 3595);
FORCEPROP 2 LAST CDS_LIB mstr_misc
J 0
(1080 3595);
PAINT MONO (1080 3595);
DISPLAY INVISIBLE (1080 3595);
FORCEPROP 1 LAST COMMENT_BODY TRUE
J 0
(1080 3595);
DISPLAY INVISIBLE (1080 3595);
FORCEADD DNS..2
(-2170 3595);
PAINT RED (-2170 3595);
FORCEPROP 2 LAST CDS_LIB mstr_misc
J 0
(-2170 3595);
PAINT MONO (-2170 3595);
DISPLAY INVISIBLE (-2170 3595);
FORCEPROP 1 LAST COMMENT_BODY TRUE
J 0
(-2170 3595);
DISPLAY INVISIBLE (-2170 3595);
FORCEADD DNS..2
(-1620 3595);
PAINT RED (-1620 3595);
FORCEPROP 2 LAST CDS_LIB mstr_misc
J 0
(-1620 3595);
PAINT MONO (-1620 3595);
DISPLAY INVISIBLE (-1620 3595);
FORCEPROP 1 LAST COMMENT_BODY TRUE
J 0
(-1620 3595);
DISPLAY INVISIBLE (-1620 3595);
FORCEADD DNS..2
(1630 2945);
PAINT RED (1630 2945);
FORCEPROP 2 LAST CDS_LIB mstr_misc
J 0
(1630 2945);
PAINT MONO (1630 2945);
DISPLAY INVISIBLE (1630 2945);
FORCEPROP 1 LAST COMMENT_BODY TRUE
J 0
(1630 2945);
DISPLAY INVISIBLE (1630 2945);
FORCEADD DNS..2
(-1895 3595);
PAINT RED (-1895 3595);
FORCEPROP 2 LAST CDS_LIB mstr_misc
J 0
(-1895 3595);
PAINT MONO (-1895 3595);
DISPLAY INVISIBLE (-1895 3595);
FORCEPROP 1 LAST COMMENT_BODY TRUE
J 0
(-1895 3595);
DISPLAY INVISIBLE (-1895 3595);
FORCEADD DNS..2
(-2170 1445);
PAINT RED (-2170 1445);
FORCEPROP 2 LAST CDS_LIB mstr_misc
J 0
(-2170 1445);
PAINT MONO (-2170 1445);
DISPLAY INVISIBLE (-2170 1445);
FORCEPROP 1 LAST COMMENT_BODY TRUE
J 0
(-2170 1445);
DISPLAY INVISIBLE (-2170 1445);
WIRE 16 -1 (1075 2100)(1075 2250);
WIRE 16 -1 (-2175 2100)(-2175 2250);
WIRE 16 -1 (1075 3875)(1075 3925);
WIRE 16 -1 (1075 3875)(1350 3875);
WIRE 16 -1 (1075 3725)(1075 3875);
WIRE 16 -1 (-2175 3875)(-2175 3950);
WIRE 16 -1 (-2175 3875)(-1900 3875);
WIRE 16 -1 (-2175 3725)(-2175 3875);
WIRE 16 -1 (-1900 2800)(-1900 2875);
WIRE 16 -1 (-1625 2800)(-1625 2875);
WIRE 16 -1 (1075 1300)(1075 1375);
WIRE 16 -1 (-2175 1300)(-2175 1375);
WIRE 16 -1 (1075 2800)(1075 2875);
WIRE 16 -1 (-2175 2800)(-2175 2875);
WIRE 16 -1 (1350 2800)(1350 2875);
WIRE 16 -1 (1625 2800)(1625 2875);
WIRE 16 -1 (1075 1725)(1075 1575);
WIRE 16 -1 (1075 1900)(1075 1725);
WIRE 16 -1 (1075 1725)(2700 1725);
FORCEPROP 2 LAST SIG_NAME PU_PIROM_CPU1_SM_WP
J 0
(1590 1735);
DISPLAY 0.808511 (1590 1735);
PAINT WHITE (1590 1735);
WIRE 16 -1 (-2175 1725)(-2175 1575);
WIRE 16 -1 (-2175 1900)(-2175 1725);
WIRE 16 -1 (-2175 1725)(-550 1725);
FORCEPROP 2 LAST SIG_NAME PU_PIROM_CPU0_SM_WP
J 0
(-1660 1735);
DISPLAY 0.808511 (-1660 1735);
PAINT WHITE (-1660 1735);
WIRE 16 -1 (1075 3350)(1075 3075);
WIRE 16 -1 (1075 3525)(1075 3350);
WIRE 16 -1 (1075 3350)(2700 3350);
FORCEPROP 2 LAST SIG_NAME PD_PIROM_CPU1_ADDR2
J 0
(1815 3360);
DISPLAY 0.808511 (1815 3360);
PAINT WHITE (1815 3360);
WIRE 16 -1 (1350 3725)(1350 3875);
WIRE 16 -1 (1350 3875)(1625 3875);
WIRE 16 -1 (1625 3725)(1625 3875);
WIRE 16 -1 (-2175 3350)(-2175 3075);
WIRE 16 -1 (-2175 3525)(-2175 3350);
WIRE 16 -1 (-2175 3350)(-550 3350);
FORCEPROP 2 LAST SIG_NAME PD_PIROM_CPU0_ADDR2
J 0
(-1435 3360);
DISPLAY 0.808511 (-1435 3360);
PAINT WHITE (-1435 3360);
WIRE 16 -1 (-1900 3725)(-1900 3875);
WIRE 16 -1 (-1900 3875)(-1625 3875);
WIRE 16 -1 (-1625 3725)(-1625 3875);
WIRE 16 -1 (1350 3275)(1350 3075);
WIRE 16 -1 (1350 3525)(1350 3275);
WIRE 16 -1 (1350 3275)(2700 3275);
FORCEPROP 2 LAST SIG_NAME PD_PIROM_CPU1_ADDR1
J 0
(1815 3285);
DISPLAY 0.808511 (1815 3285);
PAINT WHITE (1815 3285);
WIRE 16 -1 (1625 3200)(1625 3075);
WIRE 16 -1 (1625 3525)(1625 3200);
WIRE 16 -1 (1625 3200)(2700 3200);
FORCEPROP 2 LAST SIG_NAME PU_PIROM_CPU1_ADDR0
J 0
(1815 3210);
DISPLAY 0.808511 (1815 3210);
PAINT WHITE (1815 3210);
WIRE 16 -1 (-1900 3275)(-1900 3075);
WIRE 16 -1 (-1900 3525)(-1900 3275);
WIRE 16 -1 (-1900 3275)(-550 3275);
FORCEPROP 2 LAST SIG_NAME PD_PIROM_CPU0_ADDR1
J 0
(-1435 3285);
DISPLAY 0.808511 (-1435 3285);
PAINT WHITE (-1435 3285);
WIRE 16 -1 (-1625 3200)(-1625 3075);
WIRE 16 -1 (-1625 3525)(-1625 3200);
WIRE 16 -1 (-1625 3200)(-550 3200);
FORCEPROP 2 LAST SIG_NAME PD_PIROM_CPU0_ADDR0
J 0
(-1435 3210);
DISPLAY 0.808511 (-1435 3210);
PAINT WHITE (-1435 3210);
DOT 1 (-2175 1725);
DOT 1 (-2175 3350);
DOT 1 (-2175 3875);
DOT 1 (-1625 3200);
DOT 1 (-1900 3875);
DOT 1 (1075 1725);
DOT 1 (1075 3350);
DOT 1 (1075 3875);
DOT 1 (1625 3200);
DOT 1 (1350 3275);
DOT 1 (1350 3875);
DOT 1 (-1900 3275);
FORCENOTE
CPU0 ADDR: 000
(-1275 3825) 0;
DISPLAY LEFT (-1275 3825);
DISPLAY 1.595745 (-1275 3825);
PAINT SKYBLUE (-1275 3825);
FORCENOTE
CPU1 ADDR: 001
(1975 3825) 0;
DISPLAY LEFT (1975 3825);
DISPLAY 1.595745 (1975 3825);
PAINT SKYBLUE (1975 3825);
QUIT
